(kicad_pcb
	(version 20260206)
	(generator "pcbnew")
	(generator_version "10.0")
	(general
		(thickness 1.6)
		(legacy_teardrops no)
	)
	(paper "A4")
	(title_block
		(title "Bryce Canyon_F.DPB_16315-1-OCP.brd")
		(comment 1 "Bryce Canyon / footprint 939 of 2223 (DPB1), pads 74-150 of 150")
	)
	(layers
		(0 "F.Cu" signal "TOP")
		(4 "In1.Cu" signal "L2GND")
		(6 "In2.Cu" signal "L3")
		(8 "In3.Cu" signal "L4GND")
		(10 "In4.Cu" signal "L5")
		(12 "In5.Cu" signal "L6VCC")
		(14 "In6.Cu" signal "L7VCC")
		(16 "In7.Cu" signal "L8")
		(18 "In8.Cu" signal "L9GND")
		(20 "In9.Cu" signal "L10")
		(22 "In10.Cu" signal "L11GND")
		(2 "B.Cu" signal "BOTTOM")
		(9 "F.Adhes" user "F.Adhesive")
		(11 "B.Adhes" user "B.Adhesive")
		(13 "F.Paste" user "Package Geometry/Pastemask Top")
		(15 "B.Paste" user "Package Geometry/Pastemask Bottom")
		(5 "F.SilkS" user "Ref Des/Silkscreen Top")
		(7 "B.SilkS" user "Ref Des/Silkscreen Bottom")
		(1 "F.Mask" user "Board Geometry/Soldermask Top")
		(3 "B.Mask" user "Board Geometry/Soldermask Bottom")
		(17 "Dwgs.User" user "User.Drawings")
		(19 "Cmts.User" user "User.Comments")
		(21 "Eco1.User" user "User.Eco1")
		(23 "Eco2.User" user "User.Eco2")
		(25 "Edge.Cuts" user "Board Geometry/Outline")
		(27 "Margin" user)
		(31 "F.CrtYd" user "Package Geometry/Place Bound Top")
		(29 "B.CrtYd" user "Package Geometry/Place Bound Bottom")
		(35 "F.Fab" user "Ref Des/Assembly Top")
		(33 "B.Fab" user "Ref Des/Assembly Bottom")
	)
	(footprint ""
		(layer "F.Cu")
		(at 210.000088 -419.200076)
		(property "Reference" "DPB1"
			(at 0 0 0)
			(layer "F.SilkS")
			(hide yes)
			(effects
				(font
					(size 1.27 1.27)
				)
			)
		)
		(property "Value" "AMP-CONN150-12R-4-GP"
			(at -12.8016 -12.1412 0)
			(unlocked yes)
			(layer "F.Fab")
			(hide yes)
			(effects
				(font
					(size 1.016 1.016)
					(thickness 0.1524)
				)
			)
		)
		(property "Device Type" "PREFIT-150P-258346H582"
			(at -12.8016 -13.6652 0)
			(unlocked yes)
			(layer "F.Fab")
			(hide yes)
			(effects
				(font
					(size 1.016 1.016)
					(thickness 0.1524)
				)
			)
		)
		(duplicate_pad_numbers_are_jumpers no)
		(pad "G2" thru_hole circle
			(at 1.800098 11.800078)
			(size 0.762 0.762)
			(drill 0.359918)
			(layers "*.Cu" "*.Mask")
			(remove_unused_layers no)
			(net "PCIE_SCC_B_TO_COMP_B_1_DP")
			(clearance 0.1651)
			(thermal_gap 0.1651)
		)
		(pad "G3" thru_hole circle
			(at 3.599942 10.80008)
			(size 0.762 0.762)
			(drill 0.359918)
			(layers "*.Cu" "*.Mask")
			(remove_unused_layers no)
			(net "PCIE_SCC_B_TO_COMP_B_2_DP")
			(clearance 0.1651)
			(thermal_gap 0.1651)
		)
		(pad "G4" thru_hole circle
			(at 5.40004 11.800078)
			(size 0.762 0.762)
			(drill 0.359918)
			(layers "*.Cu" "*.Mask")
			(remove_unused_layers no)
			(net "PCIE_SCC_B_TO_COMP_B_3_DP")
			(clearance 0.1651)
			(thermal_gap 0.1651)
		)
		(pad "G5" thru_hole circle
			(at 7.199884 10.80008)
			(size 0.762 0.762)
			(drill 0.359918)
			(layers "*.Cu" "*.Mask")
			(remove_unused_layers no)
			(net "PCIE_SCC_B_TO_COMP_B_4_DP")
			(clearance 0.1651)
			(thermal_gap 0.1651)
		)
		(pad "G6" thru_hole circle
			(at 8.999982 11.800078)
			(size 0.762 0.762)
			(drill 0.359918)
			(layers "*.Cu" "*.Mask")
			(remove_unused_layers no)
			(net "PCIE_SCC_B_TO_COMP_B_5_DP")
			(clearance 0.1651)
			(thermal_gap 0.1651)
		)
		(pad "G7" thru_hole circle
			(at 10.80008 10.80008)
			(size 0.762 0.762)
			(drill 0.359918)
			(layers "*.Cu" "*.Mask")
			(remove_unused_layers no)
			(net "PCIE_SCC_B_TO_COMP_B_6_DP")
			(clearance 0.1651)
			(thermal_gap 0.1651)
		)
		(pad "G8" thru_hole circle
			(at 12.599924 11.800078)
			(size 0.762 0.762)
			(drill 0.359918)
			(layers "*.Cu" "*.Mask")
			(remove_unused_layers no)
			(net "PCIE_SCC_B_TO_COMP_B_7_DP")
			(clearance 0.1651)
			(thermal_gap 0.1651)
		)
		(pad "G9" thru_hole circle
			(at 16.20012 7.199884)
			(size 0.762 0.762)
			(drill 0.359918)
			(layers "*.Cu" "*.Mask")
			(remove_unused_layers no)
			(net "P12V_B_PGOOD")
			(clearance 0.1651)
			(thermal_gap 0.1651)
		)
		(pad "G10" thru_hole circle
			(at 17.999964 7.100062)
			(size 0.762 0.762)
			(drill 0.359918)
			(layers "*.Cu" "*.Mask")
			(remove_unused_layers no)
			(net "IOM_B_INS_N")
			(clearance 0.1651)
			(thermal_gap 0.1651)
		)
		(pad "G11" thru_hole circle
			(at 19.800062 7.199884)
			(size 0.762 0.762)
			(drill 0.359918)
			(layers "*.Cu" "*.Mask")
			(remove_unused_layers no)
			(net "DRIVE_B_30_ACT")
			(clearance 0.1651)
			(thermal_gap 0.1651)
		)
		(pad "G12" thru_hole circle
			(at 21.599906 7.100062)
			(size 0.762 0.762)
			(drill 0.359918)
			(layers "*.Cu" "*.Mask")
			(remove_unused_layers no)
			(net "FRONT_FAN_LED0")
			(clearance 0.1651)
			(thermal_gap 0.1651)
		)
		(pad "GND1" thru_hole circle
			(at 0 2.500122)
			(size 0.762 0.762)
			(drill 0.359918)
			(layers "*.Cu" "*.Mask")
			(remove_unused_layers no)
			(net "GND")
			(clearance 0.1651)
			(thermal_gap 0.1651)
		)
		(pad "GND2" thru_hole circle
			(at 0 6.100064)
			(size 0.762 0.762)
			(drill 0.359918)
			(layers "*.Cu" "*.Mask")
			(remove_unused_layers no)
			(net "GND")
			(clearance 0.1651)
			(thermal_gap 0.1651)
		)
		(pad "GND3" thru_hole circle
			(at 0 9.700006)
			(size 0.762 0.762)
			(drill 0.359918)
			(layers "*.Cu" "*.Mask")
			(remove_unused_layers no)
			(net "GND")
			(clearance 0.1651)
			(thermal_gap 0.1651)
		)
		(pad "GND4" thru_hole circle
			(at 0 13.299948)
			(size 0.762 0.762)
			(drill 0.359918)
			(layers "*.Cu" "*.Mask")
			(remove_unused_layers no)
			(net "GND")
			(clearance 0.1651)
			(thermal_gap 0.1651)
		)
		(pad "GND5" thru_hole circle
			(at 1.800098 -0.100076)
			(size 0.762 0.762)
			(drill 0.359918)
			(layers "*.Cu" "*.Mask")
			(remove_unused_layers no)
			(net "GND")
			(clearance 0.1651)
			(thermal_gap 0.1651)
		)
		(pad "GND6" thru_hole circle
			(at 1.800098 3.50012)
			(size 0.762 0.762)
			(drill 0.359918)
			(layers "*.Cu" "*.Mask")
			(remove_unused_layers no)
			(net "GND")
			(clearance 0.1651)
			(thermal_gap 0.1651)
		)
		(pad "GND7" thru_hole circle
			(at 1.800098 7.100062)
			(size 0.762 0.762)
			(drill 0.359918)
			(layers "*.Cu" "*.Mask")
			(remove_unused_layers no)
			(net "GND")
			(clearance 0.1651)
			(thermal_gap 0.1651)
		)
		(pad "GND8" thru_hole circle
			(at 1.800098 10.700004)
			(size 0.762 0.762)
			(drill 0.359918)
			(layers "*.Cu" "*.Mask")
			(remove_unused_layers no)
			(net "GND")
			(clearance 0.1651)
			(thermal_gap 0.1651)
		)
		(pad "GND9" thru_hole circle
			(at 1.800098 14.299946)
			(size 0.762 0.762)
			(drill 0.359918)
			(layers "*.Cu" "*.Mask")
			(remove_unused_layers no)
			(net "GND")
			(clearance 0.1651)
			(thermal_gap 0.1651)
		)
		(pad "GND10" thru_hole circle
			(at 3.599942 2.500122)
			(size 0.762 0.762)
			(drill 0.359918)
			(layers "*.Cu" "*.Mask")
			(remove_unused_layers no)
			(net "GND")
			(clearance 0.1651)
			(thermal_gap 0.1651)
		)
		(pad "GND11" thru_hole circle
			(at 3.599942 6.100064)
			(size 0.762 0.762)
			(drill 0.359918)
			(layers "*.Cu" "*.Mask")
			(remove_unused_layers no)
			(net "GND")
			(clearance 0.1651)
			(thermal_gap 0.1651)
		)
		(pad "GND12" thru_hole circle
			(at 3.599942 9.700006)
			(size 0.762 0.762)
			(drill 0.359918)
			(layers "*.Cu" "*.Mask")
			(remove_unused_layers no)
			(net "GND")
			(clearance 0.1651)
			(thermal_gap 0.1651)
		)
		(pad "GND13" thru_hole circle
			(at 3.599942 13.299948)
			(size 0.762 0.762)
			(drill 0.359918)
			(layers "*.Cu" "*.Mask")
			(remove_unused_layers no)
			(net "GND")
			(clearance 0.1651)
			(thermal_gap 0.1651)
		)
		(pad "GND14" thru_hole circle
			(at 5.40004 -0.100076)
			(size 0.762 0.762)
			(drill 0.359918)
			(layers "*.Cu" "*.Mask")
			(remove_unused_layers no)
			(net "GND")
			(clearance 0.1651)
			(thermal_gap 0.1651)
		)
		(pad "GND15" thru_hole circle
			(at 5.40004 3.50012)
			(size 0.762 0.762)
			(drill 0.359918)
			(layers "*.Cu" "*.Mask")
			(remove_unused_layers no)
			(net "GND")
			(clearance 0.1651)
			(thermal_gap 0.1651)
		)
		(pad "GND16" thru_hole circle
			(at 5.40004 7.100062)
			(size 0.762 0.762)
			(drill 0.359918)
			(layers "*.Cu" "*.Mask")
			(remove_unused_layers no)
			(net "GND")
			(clearance 0.1651)
			(thermal_gap 0.1651)
		)
		(pad "GND17" thru_hole circle
			(at 5.40004 10.700004)
			(size 0.762 0.762)
			(drill 0.359918)
			(layers "*.Cu" "*.Mask")
			(remove_unused_layers no)
			(net "GND")
			(clearance 0.1651)
			(thermal_gap 0.1651)
		)
		(pad "GND18" thru_hole circle
			(at 5.40004 14.299946)
			(size 0.762 0.762)
			(drill 0.359918)
			(layers "*.Cu" "*.Mask")
			(remove_unused_layers no)
			(net "GND")
			(clearance 0.1651)
			(thermal_gap 0.1651)
		)
		(pad "GND19" thru_hole circle
			(at 7.199884 2.500122)
			(size 0.762 0.762)
			(drill 0.359918)
			(layers "*.Cu" "*.Mask")
			(remove_unused_layers no)
			(net "GND")
			(clearance 0.1651)
			(thermal_gap 0.1651)
		)
		(pad "GND20" thru_hole circle
			(at 7.199884 6.100064)
			(size 0.762 0.762)
			(drill 0.359918)
			(layers "*.Cu" "*.Mask")
			(remove_unused_layers no)
			(net "GND")
			(clearance 0.1651)
			(thermal_gap 0.1651)
		)
		(pad "GND21" thru_hole circle
			(at 7.199884 9.700006)
			(size 0.762 0.762)
			(drill 0.359918)
			(layers "*.Cu" "*.Mask")
			(remove_unused_layers no)
			(net "GND")
			(clearance 0.1651)
			(thermal_gap 0.1651)
		)
		(pad "GND22" thru_hole circle
			(at 7.199884 13.299948)
			(size 0.762 0.762)
			(drill 0.359918)
			(layers "*.Cu" "*.Mask")
			(remove_unused_layers no)
			(net "GND")
			(clearance 0.1651)
			(thermal_gap 0.1651)
		)
		(pad "GND23" thru_hole circle
			(at 8.999982 -0.100076)
			(size 0.762 0.762)
			(drill 0.359918)
			(layers "*.Cu" "*.Mask")
			(remove_unused_layers no)
			(net "GND")
			(clearance 0.1651)
			(thermal_gap 0.1651)
		)
		(pad "GND24" thru_hole circle
			(at 8.999982 3.50012)
			(size 0.762 0.762)
			(drill 0.359918)
			(layers "*.Cu" "*.Mask")
			(remove_unused_layers no)
			(net "GND")
			(clearance 0.1651)
			(thermal_gap 0.1651)
		)
		(pad "GND25" thru_hole circle
			(at 8.999982 7.100062)
			(size 0.762 0.762)
			(drill 0.359918)
			(layers "*.Cu" "*.Mask")
			(remove_unused_layers no)
			(net "GND")
			(clearance 0.1651)
			(thermal_gap 0.1651)
		)
		(pad "GND26" thru_hole circle
			(at 8.999982 10.700004)
			(size 0.762 0.762)
			(drill 0.359918)
			(layers "*.Cu" "*.Mask")
			(remove_unused_layers no)
			(net "GND")
			(clearance 0.1651)
			(thermal_gap 0.1651)
		)
		(pad "GND27" thru_hole circle
			(at 8.999982 14.299946)
			(size 0.762 0.762)
			(drill 0.359918)
			(layers "*.Cu" "*.Mask")
			(remove_unused_layers no)
			(net "GND")
			(clearance 0.1651)
			(thermal_gap 0.1651)
		)
		(pad "GND28" thru_hole circle
			(at 10.80008 2.500122)
			(size 0.762 0.762)
			(drill 0.359918)
			(layers "*.Cu" "*.Mask")
			(remove_unused_layers no)
			(net "GND")
			(clearance 0.1651)
			(thermal_gap 0.1651)
		)
		(pad "GND29" thru_hole circle
			(at 10.80008 6.100064)
			(size 0.762 0.762)
			(drill 0.359918)
			(layers "*.Cu" "*.Mask")
			(remove_unused_layers no)
			(net "GND")
			(clearance 0.1651)
			(thermal_gap 0.1651)
		)
		(pad "GND30" thru_hole circle
			(at 10.80008 9.700006)
			(size 0.762 0.762)
			(drill 0.359918)
			(layers "*.Cu" "*.Mask")
			(remove_unused_layers no)
			(net "GND")
			(clearance 0.1651)
			(thermal_gap 0.1651)
		)
		(pad "GND31" thru_hole circle
			(at 10.80008 13.299948)
			(size 0.762 0.762)
			(drill 0.359918)
			(layers "*.Cu" "*.Mask")
			(remove_unused_layers no)
			(net "GND")
			(clearance 0.1651)
			(thermal_gap 0.1651)
		)
		(pad "GND32" thru_hole circle
			(at 12.599924 -0.100076)
			(size 0.762 0.762)
			(drill 0.359918)
			(layers "*.Cu" "*.Mask")
			(remove_unused_layers no)
			(net "GND")
			(clearance 0.1651)
			(thermal_gap 0.1651)
		)
		(pad "GND33" thru_hole circle
			(at 12.599924 3.50012)
			(size 0.762 0.762)
			(drill 0.359918)
			(layers "*.Cu" "*.Mask")
			(remove_unused_layers no)
			(net "GND")
			(clearance 0.1651)
			(thermal_gap 0.1651)
		)
		(pad "GND34" thru_hole circle
			(at 12.599924 7.100062)
			(size 0.762 0.762)
			(drill 0.359918)
			(layers "*.Cu" "*.Mask")
			(remove_unused_layers no)
			(net "GND")
			(clearance 0.1651)
			(thermal_gap 0.1651)
		)
		(pad "GND35" thru_hole circle
			(at 12.599924 10.700004)
			(size 0.762 0.762)
			(drill 0.359918)
			(layers "*.Cu" "*.Mask")
			(remove_unused_layers no)
			(net "GND")
			(clearance 0.1651)
			(thermal_gap 0.1651)
		)
		(pad "GND36" thru_hole circle
			(at 12.599924 14.299946)
			(size 0.762 0.762)
			(drill 0.359918)
			(layers "*.Cu" "*.Mask")
			(remove_unused_layers no)
			(net "GND")
			(clearance 0.1651)
			(thermal_gap 0.1651)
		)
		(pad "H1" thru_hole circle
			(at 0 12.199874)
			(size 0.762 0.762)
			(drill 0.359918)
			(layers "*.Cu" "*.Mask")
			(remove_unused_layers no)
			(net "PCIE_SCC_B_TO_COMP_B_0_DN")
			(clearance 0.1651)
			(thermal_gap 0.1651)
		)
		(pad "H2" thru_hole circle
			(at 1.800098 13.200126)
			(size 0.762 0.762)
			(drill 0.359918)
			(layers "*.Cu" "*.Mask")
			(remove_unused_layers no)
			(net "PCIE_SCC_B_TO_COMP_B_1_DN")
			(clearance 0.1651)
			(thermal_gap 0.1651)
		)
		(pad "H3" thru_hole circle
			(at 3.599942 12.199874)
			(size 0.762 0.762)
			(drill 0.359918)
			(layers "*.Cu" "*.Mask")
			(remove_unused_layers no)
			(net "PCIE_SCC_B_TO_COMP_B_2_DN")
			(clearance 0.1651)
			(thermal_gap 0.1651)
		)
		(pad "H4" thru_hole circle
			(at 5.40004 13.200126)
			(size 0.762 0.762)
			(drill 0.359918)
			(layers "*.Cu" "*.Mask")
			(remove_unused_layers no)
			(net "PCIE_SCC_B_TO_COMP_B_3_DN")
			(clearance 0.1651)
			(thermal_gap 0.1651)
		)
		(pad "H5" thru_hole circle
			(at 7.199884 12.199874)
			(size 0.762 0.762)
			(drill 0.359918)
			(layers "*.Cu" "*.Mask")
			(remove_unused_layers no)
			(net "PCIE_SCC_B_TO_COMP_B_4_DN")
			(clearance 0.1651)
			(thermal_gap 0.1651)
		)
		(pad "H6" thru_hole circle
			(at 8.999982 13.200126)
			(size 0.762 0.762)
			(drill 0.359918)
			(layers "*.Cu" "*.Mask")
			(remove_unused_layers no)
			(net "PCIE_SCC_B_TO_COMP_B_5_DN")
			(clearance 0.1651)
			(thermal_gap 0.1651)
		)
		(pad "H7" thru_hole circle
			(at 10.80008 12.199874)
			(size 0.762 0.762)
			(drill 0.359918)
			(layers "*.Cu" "*.Mask")
			(remove_unused_layers no)
			(net "PCIE_SCC_B_TO_COMP_B_6_DN")
			(clearance 0.1651)
			(thermal_gap 0.1651)
		)
		(pad "H8" thru_hole circle
			(at 12.599924 13.200126)
			(size 0.762 0.762)
			(drill 0.359918)
			(layers "*.Cu" "*.Mask")
			(remove_unused_layers no)
			(net "PCIE_SCC_B_TO_COMP_B_7_DN")
			(clearance 0.1651)
			(thermal_gap 0.1651)
		)
		(pad "H9" thru_hole circle
			(at 16.20012 8.599932)
			(size 0.762 0.762)
			(drill 0.359918)
			(layers "*.Cu" "*.Mask")
			(remove_unused_layers no)
			(net "SCC_B_STBY_PWR_EN")
			(clearance 0.1651)
			(thermal_gap 0.1651)
		)
		(pad "H10" thru_hole circle
			(at 17.999964 8.199882)
			(size 0.762 0.762)
			(drill 0.359918)
			(layers "*.Cu" "*.Mask")
			(remove_unused_layers no)
			(net "SCC_A_INS_N")
			(clearance 0.1651)
			(thermal_gap 0.1651)
		)
		(pad "H11" thru_hole circle
			(at 19.800062 8.599932)
			(size 0.762 0.762)
			(drill 0.359918)
			(layers "*.Cu" "*.Mask")
			(remove_unused_layers no)
			(net "DRIVE_B_31_ACT")
			(clearance 0.1651)
			(thermal_gap 0.1651)
		)
		(pad "H12" thru_hole circle
			(at 21.599906 8.199882)
			(size 0.762 0.762)
			(drill 0.359918)
			(layers "*.Cu" "*.Mask")
			(remove_unused_layers no)
			(net "FRONT_FAN_LED1")
			(clearance 0.1651)
			(thermal_gap 0.1651)
		)
		(pad "J9" thru_hole circle
			(at 16.20012 9.700006)
			(size 0.762 0.762)
			(drill 0.359918)
			(layers "*.Cu" "*.Mask")
			(remove_unused_layers no)
			(net "DPB_PWR_BTN_BUF_B")
			(clearance 0.1651)
			(thermal_gap 0.1651)
		)
		(pad "J10" thru_hole circle
			(at 17.999964 9.59993)
			(size 0.762 0.762)
			(drill 0.359918)
			(layers "*.Cu" "*.Mask")
			(remove_unused_layers no)
			(net "SCC_B_INS_N")
			(clearance 0.1651)
			(thermal_gap 0.1651)
		)
		(pad "J11" thru_hole circle
			(at 19.800062 9.700006)
			(size 0.762 0.762)
			(drill 0.359918)
			(layers "*.Cu" "*.Mask")
			(remove_unused_layers no)
			(net "DRIVE_B_32_ACT")
			(clearance 0.1651)
			(thermal_gap 0.1651)
		)
		(pad "J12" thru_hole circle
			(at 21.599906 9.59993)
			(size 0.762 0.762)
			(drill 0.359918)
			(layers "*.Cu" "*.Mask")
			(remove_unused_layers no)
			(net "FRONT_FAN_LED2")
			(clearance 0.1651)
			(thermal_gap 0.1651)
		)
		(pad "K9" thru_hole circle
			(at 16.20012 10.80008)
			(size 0.762 0.762)
			(drill 0.359918)
			(layers "*.Cu" "*.Mask")
			(remove_unused_layers no)
			(net "SCC_B_FAULT_LED")
			(clearance 0.1651)
			(thermal_gap 0.1651)
		)
		(pad "K10" thru_hole circle
			(at 17.999964 10.700004)
			(size 0.762 0.762)
			(drill 0.359918)
			(layers "*.Cu" "*.Mask")
			(remove_unused_layers no)
			(net "SCC_B_TYPE_0")
			(clearance 0.1651)
			(thermal_gap 0.1651)
		)
		(pad "K11" thru_hole circle
			(at 19.800062 10.80008)
			(size 0.762 0.762)
			(drill 0.359918)
			(layers "*.Cu" "*.Mask")
			(remove_unused_layers no)
			(net "DRIVE_B_33_ACT")
			(clearance 0.1651)
			(thermal_gap 0.1651)
		)
		(pad "K12" thru_hole circle
			(at 21.599906 10.700004)
			(size 0.762 0.762)
			(drill 0.359918)
			(layers "*.Cu" "*.Mask")
			(remove_unused_layers no)
			(net "FRONT_FAN_LED3")
			(clearance 0.1651)
			(thermal_gap 0.1651)
		)
		(pad "L9" thru_hole circle
			(at 16.20012 12.199874)
			(size 0.762 0.762)
			(drill 0.359918)
			(layers "*.Cu" "*.Mask")
			(remove_unused_layers no)
			(net "SCC_B_TYPE_3")
			(clearance 0.1651)
			(thermal_gap 0.1651)
		)
		(pad "L10" thru_hole circle
			(at 17.999964 11.800078)
			(size 0.762 0.762)
			(drill 0.359918)
			(layers "*.Cu" "*.Mask")
			(remove_unused_layers no)
			(net "SCC_B_TYPE_1")
			(clearance 0.1651)
			(thermal_gap 0.1651)
		)
		(pad "L11" thru_hole circle
			(at 19.800062 12.199874)
			(size 0.762 0.762)
			(drill 0.359918)
			(layers "*.Cu" "*.Mask")
			(remove_unused_layers no)
			(net "DRIVE_B_34_ACT")
			(clearance 0.1651)
			(thermal_gap 0.1651)
		)
		(pad "L12" thru_hole circle
			(at 21.599906 11.800078)
			(size 0.762 0.762)
			(drill 0.359918)
			(layers "*.Cu" "*.Mask")
			(remove_unused_layers no)
			(net "P3V3_STBY_A")
			(clearance 0.1651)
			(thermal_gap 0.1651)
		)
		(pad "M9" thru_hole circle
			(at 16.20012 13.299948)
			(size 0.762 0.762)
			(drill 0.359918)
			(layers "*.Cu" "*.Mask")
			(remove_unused_layers no)
			(net "GND")
			(clearance 0.1651)
			(thermal_gap 0.1651)
		)
		(pad "M10" thru_hole circle
			(at 17.999964 13.200126)
			(size 0.762 0.762)
			(drill 0.359918)
			(layers "*.Cu" "*.Mask")
			(remove_unused_layers no)
			(net "SCC_B_TYPE_2")
			(clearance 0.1651)
			(thermal_gap 0.1651)
		)
		(pad "M11" thru_hole circle
			(at 19.800062 13.299948)
			(size 0.762 0.762)
			(drill 0.359918)
			(layers "*.Cu" "*.Mask")
			(remove_unused_layers no)
			(net "DRIVE_B_35_ACT")
			(clearance 0.1651)
			(thermal_gap 0.1651)
		)
		(pad "M12" thru_hole circle
			(at 21.599906 13.200126)
			(size 0.762 0.762)
			(drill 0.359918)
			(layers "*.Cu" "*.Mask")
			(remove_unused_layers no)
			(net "P3V3_STBY_B")
			(clearance 0.1651)
			(thermal_gap 0.1651)
		)
		(pad "N10" thru_hole circle
			(at 17.999964 14.299946)
			(size 0.762 0.762)
			(drill 0.359918)
			(layers "*.Cu" "*.Mask")
			(remove_unused_layers no)
			(net "GND")
			(clearance 0.1651)
			(thermal_gap 0.1651)
		)
		(pad "N12" thru_hole circle
			(at 21.599906 14.299946)
			(size 0.762 0.762)
			(drill 0.359918)
			(layers "*.Cu" "*.Mask")
			(remove_unused_layers no)
			(net "P5V_B")
			(clearance 0.1651)
			(thermal_gap 0.1651)
		)
	)
)
